# BASEBOARD_FAB2 (Tioga Pass) — schematic parts with pin connectivity, parts 3137–3291 of 4751; source: Cadence DE-HDL packaged netlist (pstxprt.dat, pstxnet.dat, pstchip.dat)

R3P7  RES  1.00K 1% EMPTY  pkg 0402  page 133 : 1 = P1V05_PCH_STBY ; 2 = FM_PRSNT_2_1_N
R3P8  RES  1.00K 1% CHIP  pkg 0402  page 133 : 1 = P1V05_PCH_STBY ; 2 = FM_PRSNT_2_6_N
R3P11  RES  0.0 5% CHIP  pkg 0402  page 211 : 1 = SVID_DIO0_CPU0_R ; 2 = SVID_VDIO_PVCCIO_CPU0
R3P12  RES  100.0K 1% CHIP  pkg 0402  page 211 : 1 = VR_FET_SW_P12V_STBY_PVCCIO_CPU0 ; 2 = VR_PVCCIO_CPU0_VINSEN
R3P13  RES  100.0 1% CHIP  pkg 0402  page 211 : 1 = PVCCIO_CPU0 ; 2 = SVID_DIO0_CPU0_R
R3P15  RES  150.0 1% CHIP  pkg 0402  page 211 : 1 = SVID_CLK0_CPU0_R ; 2 = SVID_CLK_PVCCIO_CPU0
R3P16  RES  1.5K 1% CHIP  pkg 0402  page 211 : 1 = VR_PVCCIO_CPU0_VINSEN ; 2 = GND
R3P17  RES  49.9 1% CHIP  pkg 0402  page 211 : 1 = PVCCIO_CPU0 ; 2 = SVID_CLK0_CPU0_R
R3P18  RES  1.00K 1% CHIP  pkg 0402  page 211 : 1 = P3V3_STBY ; 2 = IRQ_PVCCIO_CPU0_VRHOT_N
R3P20  RES  22.1 1.0% CHIP  pkg 0402  page 211 : 1 = PWRGD_PVCCIO_CPU0_R ; 2 = PWRGD_PVCCIO_CPU0
R3P21  RES  100.0K 1% EMPTY  pkg 0402  page 211 : 1 = P3V3_STBY ; 2 = VR_PVCCIO_CPU0_EN
R3P22  RES  0.0 5% CHIP  pkg 0402  page 211 : 1 = P3V3_STBY ; 2 = VR_PVCCIO_CPU0_VDD
R3P25  RES  1.00K 1% CHIP  pkg 0402  page 211 : 1 = P3V3_STBY ; 2 = PWRGD_PVCCIO_CPU0_R
R3P26  RES  0.0 5% CHIP  pkg 0402  page 211 : 1 = FM_PVCCIO_CPU0_EN ; 2 = VR_PVCCIO_CPU0_EN
R3P29  RES  64.9 1.0% CHIP  pkg 0402  page 96 : 1 = PVDDQ_DEF ; 2 = PWRGD_CPU0_DRAMPWROK_DEF_G
R3P32  RES  1.00K 1% CHIP  pkg 0402  page 96 : 1 = GND ; 2 = PD_GTL2014_1_VREF
R3P34  RES  0.0 5% CHIP  pkg 0402  page 190 : 1 = RST_CPU0_LVC3_R1_N ; 2 = RST_CPU0_LVC3_N
R3P35  RES  0.0 5% CHIP  pkg 0402  page 190 : 1 = RST_CPU1_LVC3_R1_N ; 2 = RST_CPU1_LVC3_N
R3P36  RES  1.00K 1% CHIP  pkg 0402  page 96 : 1 = P3V3_STBY ; 2 = PU_GTL2014_1_DIR
R3P38  RES  64.9 1.0% CHIP  pkg 0402  page 96 : 1 = PVDDQ_ABC ; 2 = PWRGD_CPU0_DRAMPWROK_ABC_G
R3P41  RES  75 1.0% CHIP  pkg 0402  page 92 : 1 = PVCCIO_CPU1 ; 2 = H_CPU1_THERMTRIP_G_N
R3P42  RES  33.2 1% CHIP  pkg 0402  page 92 : 1 = FM_CPU1_THERMTRIP_LVT3_R_N ; 2 = FM_CPU1_THERMTRIP_LVT3_N
R3P43  RES  33.2 1% CHIP  pkg 0402  page 92 : 1 = FM_CPU_CATERR_LVT3_R2_N ; 2 = FM_CPU_CATERR_LVT3_N
R3P44  RES  4.75K 1% CHIP  pkg 0402  page 196 : 1 = P3V3_STBY ; 2 = PWRGD_DSW_PWROK
R3P45  374R2F-1-GP  1%  pkg SMD-RG  page 92 : 1 = P3V3 ; 2 = P0V7_GTL2104_VREF_1
R3P46  RES  33.2 1% CHIP  pkg 0402  page 92 : 1 = FM_CPU1_FIVR_FAULT_R_LVT3 ; 2 = FM_CPU1_FIVR_FAULT_LVT3
R3P48  RES  90.9K 1% CHIP  pkg 0402  page 196 : 1 = P12V_STBY ; 2 = VSENSE_P12V_ADM1085
R3P49  RES  100.0 1% CHIP  pkg 0402  page 92 : 1 = P0V7_GTL2104_VREF_1 ; 2 = GND
R3P50  RES  10.0K 1% EMPTY  pkg 0402  page 196 : 1 = P3V3_STBY ; 2 = PWRGD_P3V3_STBY
R3P51  RES  6.34K 1% CHIP  pkg 0402  page 196 : 1 = VSENSE_P12V_ADM1085 ; 2 = GND
R3P53  RES  4.75K 1% CHIP  pkg 0402  page 133 : 1 = P1V05_PCH_STBY ; 2 = FM_OCP_MEZZC_PRES_1V05_PCH_N
R3P54  RES  3.32K 1% EMPTY  pkg 0402  page 156 : 1 = P3V3_STBY ; 2 = FM_CPU0_SM_WP
R3P56  RES  1.00K 1% CHIP  pkg 0402  page 156 : 1 = FM_CPU0_SM_WP ; 2 = GND
R3P58  RES  0.0 5% CHIP  pkg 0402  page 92 : 1 = H_CPU1_CATERR_G_N ; 2 = H_CPU_CATERR_G_N
R3P59  RES  0.0 5% CHIP  pkg 0402  page 92 : 1 = H_CPU0_CATERR_G_N ; 2 = H_CPU_CATERR_G_N
R3P60  RES  240 1.0% CHIP  pkg 0402  page 99 : 1 = PVCCIO_CPU0 ; 2 = SMB_DDR_DEF_SCL_G
R3P61  RES  2.26K 1.0% CHIP  pkg 0402  page 181 : 1 = P3V3_STBY ; 2 = FM_MB_SLOT_ID2
R3P62  RES  4.75K 1% EMPTY  pkg 0402  page 126 : 1 = P3V3_STBY ; 2 = FM_FLASH_ATTACH_CFG_STRAP
R3P63  RES  0.0 5% EMPTY  pkg 0402  page 152 : 1 = H_CPU1_MEMGHJ_MEMHOT_LVT3_N ; 2 = H_CPU1_MEMGHJ_MEMHOT_PCH_N
R3P64  RES  1.00K 1% EMPTY  pkg 0402  page 126 : 1 = FM_FLASH_ATTACH_CFG_STRAP ; 2 = GND
R3R1  RES  1.00K 1% CHIP  pkg 0402  page 92 : 1 = PD_GTL2104_DIR_1 ; 2 = GND
R3R2  RES  1.00K 1% CHIP  pkg 0402  page 92 : 1 = H_CPU1_FIVR_FAULT_G ; 2 = GND
R3R3  RES  33.2 1% CHIP  pkg 0402  page 92 : 1 = PWRGD_CPUPWRGD_R1 ; 2 = PWRGD_CPUPWRGD
R3R4  RES  4.75K 1% CHIP  pkg 0402  page 94 : 1 = P3V3 ; 2 = H_CPU0_MEMDEF_MEMHOT
R3R5  RES  665 1.0% CHIP  pkg 0402  page 99 : 1 = PVPP_DEF ; 2 = SMB_DDR_DEF_VPP_SCL_R
R3R7  RES  10.0 1% CHIP  pkg 0402  page 99 : 1 = SMB_DDR_DEF_SCL_G_R ; 2 = SMB_DDR_DEF_SCL_G
R3R8  RES  20.0 1% CHIP  pkg 0402  page 99 : 1 = SMB_DDR_DEF_VPP_SCL_R ; 2 = SMB_DDR_DEF_VPP_SCL
R3R9  RES  20.0 1% CHIP  pkg 0402  page 99 : 1 = SMB_DDR_DEF_VPP_SDA_R ; 2 = SMB_DDR_DEF_VPP_SDA
R3R10  RES  4.75K 1% CHIP  pkg 0402  page 94 : 1 = P3V3 ; 2 = H_CPU1_MEMGHJ_MEMHOT
R3R11  RES  10.0K 1% EMPTY  pkg 0402  page 189 : 1 = FM_JTAG_PLD_EN_DEBUG ; 2 = GND
R3R12  RES  665 1.0% CHIP  pkg 0402  page 99 : 1 = PVPP_DEF ; 2 = SMB_DDR_DEF_VPP_SDA_R
R3R13  RES  240 1.0% CHIP  pkg 0402  page 99 : 1 = PVCCIO_CPU0 ; 2 = SMB_DDR_DEF_SDA_G
R3R14  RES  10.0 1% CHIP  pkg 0402  page 99 : 1 = SMB_DDR_DEF_SDA_G_R ; 2 = SMB_DDR_DEF_SDA_G
R3R15  RES  1.00K 1% CHIP  pkg 0402  page 189 : 1 = P3V3_STBY ; 2 = FM_JTAG_PLD_EN_DEBUG
R3R16  RES  4.75K 1% CHIP  pkg 0402  page 192 : 1 = PVPP_ABC ; 2 = RST_CD_CPU0_POR_N
R3T1  RES  33.2 1% CHIP  pkg 0402  page 153 : 1 = SPI_BIOS_SOCKET_IO3 ; 2 = PU_BIOS_SPI_HOLD1_N
R3T2  RES  33.2 1% CHIP  pkg 0402  page 153 : 1 = SPI_SWITCH_MISO ; 2 = SPI_MISO_R1
R3T3  RES  4.75K 1% EMPTY  pkg 0402  page 153 : 1 = P3V3_STBY ; 2 = PU_SPI1_RST
R3T4  RES  10.0K 1% CHIP  pkg 0402  page 153 : 1 = P3V3_STBY ; 2 = PU_BIOS_SPI_HOLD1_N
R3T5  RES  4.75K 1% CHIP  pkg 0402  page 153 : 1 = P3V3_STBY ; 2 = SPI_CS0_SECONDARY_R_N
R3T9  RES  10.0K 1% EMPTY  pkg 0402  page 153 : 1 = PU_BIOS_SPI_WP1_N ; 2 = GND
R3T10  RES  33.2 1% CHIP  pkg 0402  page 153 : 1 = SPI_SWITCH_MOSI ; 2 = SPI_SWITCH_MOSI_R1
R3T11  RES  49.9 1% CHIP  pkg 0402  page 215 : 1 = PVCCIO_CPU0 ; 2 = SVID_CLK1_CPU0_R
R3T12  RES  10.0K 1% CHIP  pkg 0402  page 153 : 1 = P3V3_STBY ; 2 = PU_BIOS_SPI_WP1_N
R3T13  RES  0.0 5% CHIP  pkg 0402  page 215 : 1 = P3V3_STBY ; 2 = VR_PVDDQ_ABC_VDD
R3T14  RES  10.0K 1% CHIP  pkg 0402  page 136 : 1 = FM_BIOS_USB_RECOVERY ; 2 = GND
R3U1  RES  33.2 1% CHIP  pkg 0402  page 153 : 1 = SPI_BIOS_SOCKET_IO2 ; 2 = PU_BIOS_SPI_WP1_N
R3U2  RES  100.0 1% CHIP  pkg 0402  page 215 : 1 = PVCCIO_CPU0 ; 2 = SVID_DIO1_CPU0_R
R3U4  RES  120.0 1% CHIP  pkg 0603  page 217 : 1 = PVDDQ_ABC ; 2 = GND
R3U6  RES  0.0 5% CHIP  pkg 0402  page 216 : 1 = VR_PVDDQ_ABC_PH1_VCIN ; 2 = P5V_STBY
R3U9  RES  0.0 5% CHIP  pkg 0402  page 216 : 1 = VR_PVDDQ_ABC_PH2_VCIN ; 2 = P5V_STBY
R3W1  RES  1.00K 1% CHIP  pkg 0402  page 249 : 1 = BMC_SELF_HW_D_RST ; 2 = GND
R3W2  RES  100.0K 1% CHIP  pkg 0402  page 249 : 1 = BMC_TPM_HW_C_RST ; 2 = GND
R3W3  RES  10.0K 1% EMPTY  pkg 0402  page 249 : 1 = P3V3_STBY ; 2 = FM_TPM_PRES_RST_N
R3W4  47KR2F-GP  1%  pkg RCL_GP  page 249 : 1 = FM_TPM_PRES_RST_N ; 2 = FM_TPM_PRES_RST_N_R
R3W5  RES  10.0K 1% CHIP  pkg 0402  page 249 : 1 = P3V3_STBY ; 2 = FM_TPM_PRES_RST
R3W6  RES  4.75K 1% CHIP  pkg 0402  page 249 : 1 = P3V3_STBY ; 2 = RST_BMC_EXTRST_N
R3W7  RES  4.75K 1% CHIP  pkg 0402  page 249 : 1 = P3V3_STBY ; 2 = VREF_2V2
R3W9  RES  10.0K 1% CHIP  pkg 0402  page 249 : 1 = VREF_2V2 ; 2 = GND
R3W10  RES  49.9 1% EMPTY  pkg 0402  page 92 : 1 = PVCCIO_CPU0 ; 2 = P0V7_GTL2104_VREF_1
R4A2  RES  0.0 5% CHIP  pkg 0402  page 222 : 1 = PWRGD_PVDDQ_DEF_R ; 2 = FM_PVTT_DEF_EN_R
R4A3  RES  0.0 5% CHIP  pkg 0402  page 230 : 1 = PWRGD_PVDDQ_KLM_R ; 2 = FM_PVTT_KLM_EN_R
R4A4  RES  33.2 1% CHIP  pkg 0402  page 230 : 1 = PWRGD_PVTT_KLM_CPU1_R ; 2 = PWRGD_PVTT_CPU1
R4A5  RES  10.0K 1% CHIP  pkg 0402  page 230 : 1 = P3V3 ; 2 = PWRGD_PVTT_KLM_CPU1_R
R4A6  RES  33.2 1% CHIP  pkg 0402  page 222 : 1 = PWRGD_PVTT_DEF_CPU0_R ; 2 = PWRGD_PVTT_CPU0
R4A7  RES  2.2 5% EMPTY  pkg 0402  page 234 : 1 = VR_PVPP_KLM_SNUB ; 2 = GND
R4A8  RES  0.0 5% CHIP  pkg 0402  page 156 : 1 = SMB_LAN_STBY_LVC3_SDA ; 2 = SMB_PIROM_CPU0_SDA
R4A9  RES  0.0 5% CHIP  pkg 0402  page 156 : 1 = SMB_LAN_STBY_LVC3_SCL ; 2 = SMB_PIROM_CPU0_SCL
R4B1  RES  0.0 5% CHIP  pkg 0402  page 234 : 1 = FM_PVPP_CPU1_EN ; 2 = FM_PVPP_PVDDQ_CPU1_EN_KLM
R4B2  RES  120.0 1% CHIP  pkg 0603  page 234 : 1 = PVPP_KLM ; 2 = GND
R4B3  RES  0.0 5% CHIP  pkg 0402  page 234 : 1 = PVPP_KLM ; 2 = VSENSE_PVPP_KLM
R4B4  RES  6.19K 1% CHIP  pkg 0402  page 234 : 1 = VR_FB_PVPP_KLM ; 2 = AGND_PVPP_KLM
R4B5  RES  20.0K 1% CHIP  pkg 0402  page 234 : 1 = VSENSE_PVPP_KLM ; 2 = VR_FB_PVPP_KLM
R4B6  RES  7.87K 1.0% CHIP  pkg 0402  page 234 : 1 = VR_PVPP_KLM_ISET ; 2 = AGND_PVPP_KLM
R4B7  RES  22.1 1.0% CHIP  pkg 0402  page 234 : 1 = PWRGD_PVPP_KLM_R ; 2 = PWRGD_PVPP_KLM
R4B8  RES  7.87K 1.0% CHIP  pkg 0402  page 234 : 1 = VR_COMP_RC_PVPP_KLM ; 2 = VR_FB_PVPP_KLM
R4B9  RES  1.0K 0.1% CHIP  pkg 0402  page 234 : 1 = VSENSE_PVPP_KLM ; 2 = VR_COMP_PVPP_KLM
R4B10  RES  1.00K 1% CHIP  pkg 0402  page 234 : 1 = P3V3_STBY ; 2 = PWRGD_PVPP_KLM_R
R4B12  RES  0.002 1% CHIP  pkg 1206  page 197 : 1 = P12V_STBY ; 2 = P12V_NVDIMM_DEF
R4B13  RES  0 5.0% CHIP  pkg 0603  page 234 : 1 = VR_PVPP_KLM_BOOT ; 2 = VR_PVPP_KLM_BOOT_R
R4B14  RES  0.0 5% CHIP  pkg 0402  page 234 : 1 = GND ; 2 = AGND_PVPP_KLM
R4C1  RES  100.0 1% CHIP  pkg 0402  page 205 : 1 = VSENSE_PVSA_CPU0_N ; 2 = GND
R4C2  RES  0.0 5% CHIP  pkg 0402  page 205 : 1 = VSENSE_PVSA_CPU0_N ; 2 = VSENSE_PVSA_CPU0_SKT_VRTN
R4C3  RES  1.00K 1% EMPTY  pkg 0402  page 205 : 1 = VSENSE_PVSA_CPU0_P ; 2 = VSENSE_PVSA_CPU0_N
R4C4  RES  0.0 5% CHIP  pkg 0402  page 205 : 1 = VSENSE_PVSA_CPU0_P ; 2 = VSENSE_PVSA_CPU0_SKT_VSEN
R4C5  RES  100.0 1% CHIP  pkg 0402  page 205 : 1 = VSENSE_PVSA_CPU0_P ; 2 = PVSA_CPU0
R4C8  RES  1.00K 1% CHIP  pkg 0402  page 96 : 1 = P3V3_STBY ; 2 = PU_GTL2014_2_DIR
R4C9  RES  1.00K 1% CHIP  pkg 0402  page 96 : 1 = GND ; 2 = PD_GTL2014_2_VREF
R4C10  RES  240 1.0% CHIP  pkg 0402  page 97 : 1 = PVCCIO_CPU1 ; 2 = PU_CPU1_TSC_SYNC
R4C11  RES  3.16K 1% CHIP  pkg 0402  page 193 : 1 = VR_PVCCMCP_CPU1_XADDR2 ; 2 = GND
R4C12  RES  8.06K 1% CHIP  pkg 0402  page 193 : 1 = VR_PVCCIOMCP_CPU1_XADDR1 ; 2 = GND
R4C13  RES  68.1K 1% EMPTY  pkg 0402  page 205 : 1 = VR_PVSA_CPU0_OCSET ; 2 = GND
R4D1  RES  27.4 1% CHIP  pkg 0402  page 103 : 1 = CLK_100M_CPU1_BCLK1_R_DN ; 2 = CLK_100M_CPU1_BCLK1_DN
R4D2  RES  27.4 1% CHIP  pkg 0402  page 103 : 1 = CLK_100M_CPU1_BCLK1_R_DP ; 2 = CLK_100M_CPU1_BCLK1_DP
R4D3  RES  27.4 1% CHIP  pkg 0402  page 103 : 1 = CLK_100M_CPU1_BCLK0_R_DN ; 2 = CLK_100M_CPU1_BCLK0_DN
R4D4  RES  27.4 1% CHIP  pkg 0402  page 103 : 1 = CLK_100M_CPU1_BCLK0_R_DP ; 2 = CLK_100M_CPU1_BCLK0_DP
R4D5  RES  27.4 1% CHIP  pkg 0402  page 103 : 1 = CLK_100M_CPU0_RC_REFCLK1_R_DN ; 2 = CLK_100M_CPU0_RC_REFCLK1_DN
R4D6  RES  27.4 1% CHIP  pkg 0402  page 103 : 1 = CLK_100M_CPU0_RC_REFCLK1_R_DP ; 2 = CLK_100M_CPU0_RC_REFCLK1_DP
R4D7  RES  27.4 1% CHIP  pkg 0402  page 103 : 1 = CLK_100M_CPU0_RC_REFCLK0_R_DN ; 2 = CLK_100M_CPU0_RC_REFCLK0_DN
R4D8  RES  27.4 1% CHIP  pkg 0402  page 103 : 1 = CLK_100M_CPU0_RC_REFCLK0_R_DP ; 2 = CLK_100M_CPU0_RC_REFCLK0_DP
R4D9  RES  27.4 1% CHIP  pkg 0402  page 103 : 1 = CLK_100M_CPU1_BCLK2_R_DP ; 2 = CLK_100M_CPU1_BCLK2_DP
R4D10  RES  27.4 1% CHIP  pkg 0402  page 103 : 1 = CLK_100M_CPU0_PE_REFCLK_R_DN ; 2 = CLK_100M_CPU0_PE_REFCLK_DN
R4D11  RES  27.4 1% CHIP  pkg 0402  page 103 : 1 = CLK_100M_CPU1_BCLK2_R_DN ; 2 = CLK_100M_CPU1_BCLK2_DN
R4D12  RES  27.4 1% CHIP  pkg 0402  page 103 : 1 = CLK_100M_CPU0_PE_REFCLK_R_DP ; 2 = CLK_100M_CPU0_PE_REFCLK_DP
R4D13  RES  27.4 1% CHIP  pkg 0402  page 103 : 1 = CLK_100M_CPU1_PE_REFCLK_R_DP ; 2 = CLK_100M_CPU1_PE_REFCLK_DP
R4D14  RES  27.4 1% CHIP  pkg 0402  page 103 : 1 = CLK_100M_CPU0_BCLK2_R_DN ; 2 = CLK_100M_CPU0_BCLK2_DN
R4D16  RES  27.4 1% CHIP  pkg 0402  page 103 : 1 = CLK_100M_CPU1_PE_REFCLK_R_DN ; 2 = CLK_100M_CPU1_PE_REFCLK_DN
R4D17  RES  27.4 1% CHIP  pkg 0402  page 103 : 1 = CLK_100M_CPU0_BCLK2_R_DP ; 2 = CLK_100M_CPU0_BCLK2_DP
R4D18  RES  42.2 1.0% EMPTY  pkg 0402  page 103 : 1 = CLK_100M_CPU0_BCLK1_DN ; 2 = GND
R4D19  RES  27.4 1% CHIP  pkg 0402  page 103 : 1 = CLK_100M_CPU1_RC_REFCLK0_R_DP ; 2 = CLK_100M_CPU1_RC_REFCLK0_DP
R4D20  RES  27.4 1% CHIP  pkg 0402  page 103 : 1 = CLK_100M_CPU0_BCLK1_R_DN ; 2 = CLK_100M_CPU0_BCLK1_DN
R4D21  RES  27.4 1% CHIP  pkg 0402  page 103 : 1 = CLK_100M_CPU1_RC_REFCLK0_R_DN ; 2 = CLK_100M_CPU1_RC_REFCLK0_DN
R4D22  RES  27.4 1% CHIP  pkg 0402  page 103 : 1 = CLK_100M_CPU0_BCLK1_R_DP ; 2 = CLK_100M_CPU0_BCLK1_DP
R4D23  RES  27.4 1% CHIP  pkg 0402  page 103 : 1 = CLK_100M_CPU1_RC_REFCLK1_R_DP ; 2 = CLK_100M_CPU1_RC_REFCLK1_DP
R4D24  RES  42.2 1.0% EMPTY  pkg 0402  page 103 : 1 = CLK_100M_CPU0_BCLK1_DP ; 2 = GND
R4D25  RES  27.4 1% CHIP  pkg 0402  page 103 : 1 = CLK_100M_CPU0_BCLK0_R_DN ; 2 = CLK_100M_CPU0_BCLK0_DN
R4D26  RES  0.0 5% CHIP  pkg 0402  page 201 : 1 = P3V3_STBY ; 2 = VR_PVCCIN_CPU0_VDD
R4D27  RES  100.0K 1% CHIP  pkg 0402  page 201 : 1 = VR_FET_SW_P12V_STBY_PVCCIN_CPU0 ; 2 = VR_PVCCIN_CPU0_AVINSEN
R4D28  RES  27.4 1% CHIP  pkg 0402  page 103 : 1 = CLK_100M_CPU1_RC_REFCLK1_R_DN ; 2 = CLK_100M_CPU1_RC_REFCLK1_DN
R4D29  RES  27.4 1% CHIP  pkg 0402  page 103 : 1 = CLK_100M_CPU0_BCLK0_R_DP ; 2 = CLK_100M_CPU0_BCLK0_DP
R4D31  RES  2.26K 1.0% EMPTY  pkg 0402  page 201 : 1 = P3V3_STBY ; 2 = PU_VR_PVCCIN_CPU0_IMON
R4D32  RES  1.5K 1% CHIP  pkg 0402  page 201 : 1 = VR_PVCCIN_CPU0_AVINSEN ; 2 = GND
R4D35  RES  10.0K 1% EMPTY  pkg 0402  page 102 : 1 = P3V3_DB1200 ; 2 = FM_DB1200_SMB_SA0
R4D38  RES  10.0K 1% EMPTY  pkg 0402  page 102 : 1 = P3V3_DB1200 ; 2 = FM_DB1200_SMB_SA1
R4D39  RES  10.0 1% CHIP  pkg 0402  page 201 : 1 = VSENSE_PVSA_CPU0_P ; 2 = VSENSE_PVSA_CPU0_BVSP
R4D40  RES  4.75K 1% CHIP  pkg 0402  page 102 : 1 = P3V3_DB1200 ; 2 = FM_100M_N
R4D41  RES  4.75K 1% CHIP  pkg 0402  page 102 : 1 = P3V3_DB1200 ; 2 = FM_HBW_BYPASS_LOWBW_N
R4D42  RES  1.00K 1% CHIP  pkg 0402  page 213 : 1 = P3V3_STBY ; 2 = PWRGD_PVCCIO_CPU1_R
R4D46  RES  22.1 1.0% CHIP  pkg 0402  page 213 : 1 = PWRGD_PVCCIO_CPU1_R ; 2 = PWRGD_PVCCIO_CPU1
R4D47  RES  0.0 5% CHIP  pkg 0402  page 213 : 1 = P3V3_STBY ; 2 = VR_PVCCIO_CPU1_VDD
R4D49  RES  1.00K 1% CHIP  pkg 0402  page 213 : 1 = P3V3_STBY ; 2 = IRQ_PVCCIO_CPU1_VRHOT_N
R4D51  RES  150.0 1% CHIP  pkg 0402  page 213 : 1 = SVID_CLK0_CPU1_R ; 2 = SVID_CLK_PVCCIO_CPU1
R4D54  RES  0.0 5% CHIP  pkg 0402  page 213 : 1 = SVID_DIO0_CPU1_R ; 2 = SVID_VDIO_PVCCIO_CPU1
R4D56  RES  0.0 5% CHIP  pkg 0402  page 213 : 1 = SVID_ALERT_PVCCIO_CPU1 ; 2 = SVID_ALERT0_CPU1_R_N
R4D57  RES  1.5K 1% CHIP  pkg 0402  page 213 : 1 = VR_PVCCIO_CPU1_VINSEN ; 2 = GND
